(kicad_pcb
	(version 20260206)
	(generator "pcbnew")
	(generator_version "10.0")
	(general
		(thickness 1.6)
		(legacy_teardrops no)
	)
	(paper "A4")
	(title_block
		(title "fcb — Lightning_FCB_BRD.brd")
		(comment 1 "Lightning (Wiwynn / Facebook NVMe JBOF) / footprints 5-11 of 495")
	)
	(layers
		(0 "F.Cu" signal "TOP")
		(4 "In1.Cu" signal "L2GND")
		(6 "In2.Cu" signal "L3VCC")
		(2 "B.Cu" signal "BOTTOM")
		(9 "F.Adhes" user "F.Adhesive")
		(11 "B.Adhes" user "B.Adhesive")
		(13 "F.Paste" user "Package Geometry/Pastemask Top")
		(15 "B.Paste" user "Package Geometry/Pastemask Bottom")
		(5 "F.SilkS" user "Ref Des/Silkscreen Top")
		(7 "B.SilkS" user "Ref Des/Silkscreen Bottom")
		(1 "F.Mask" user "Board Geometry/Soldermask Top")
		(3 "B.Mask" user "Board Geometry/Soldermask Bottom")
		(17 "Dwgs.User" user "User.Drawings")
		(19 "Cmts.User" user "User.Comments")
		(21 "Eco1.User" user "User.Eco1")
		(23 "Eco2.User" user "User.Eco2")
		(25 "Edge.Cuts" user "Board Geometry/Outline")
		(27 "Margin" user)
		(31 "F.CrtYd" user "Package Geometry/Place Bound Top")
		(29 "B.CrtYd" user "Package Geometry/Place Bound Bottom")
		(35 "F.Fab" user "Ref Des/Assembly Top")
		(33 "B.Fab" user "Ref Des/Assembly Bottom")
	)
	(footprint ""
		(layer "F.Cu")
		(at 26.416 -111.633)
		(property "Reference" "PQ7"
			(at 0 0 0)
			(layer "F.SilkS")
			(hide yes)
			(effects
				(font
					(size 1.27 1.27)
				)
			)
		)
		(property "Value" "PH0925CL-GP"
			(at -4.2799 -0.4572 0)
			(unlocked yes)
			(layer "F.Fab")
			(hide yes)
			(effects
				(font
					(size 1.016 1.016)
					(thickness 0.1524)
				)
			)
		)
		(property "Device Type" "LFPAK-5PH48-U"
			(at -4.2799 -1.9812 0)
			(unlocked yes)
			(layer "F.Fab")
			(hide yes)
			(effects
				(font
					(size 1.016 1.016)
					(thickness 0.1524)
				)
			)
		)
		(duplicate_pad_numbers_are_jumpers no)
		(fp_line
			(start -2.7559 -6.5532)
			(end -2.7559 1.0668)
			(stroke
				(width 0.1524)
				(type default)
			)
			(layer "F.SilkS")
		)
		(fp_line
			(start -2.7559 1.0668)
			(end 2.7559 1.0668)
			(stroke
				(width 0.1524)
				(type default)
			)
			(layer "F.SilkS")
		)
		(fp_line
			(start -1.7272 1.1684)
			(end -2.1082 1.1684)
			(stroke
				(width 0.3302)
				(type default)
			)
			(layer "F.SilkS")
		)
		(fp_line
			(start 2.7559 -6.5532)
			(end -2.7559 -6.5532)
			(stroke
				(width 0.1524)
				(type default)
			)
			(layer "F.SilkS")
		)
		(fp_line
			(start 2.7559 1.0668)
			(end 2.7559 -6.5532)
			(stroke
				(width 0.1524)
				(type default)
			)
			(layer "F.SilkS")
		)
		(fp_poly
			(pts
				(xy -2.3368 1.5748) (xy -1.905 1.143) (xy -1.4732 1.5748)
			)
			(stroke
				(width 0)
				(type default)
			)
			(fill yes)
			(layer "F.SilkS")
		)
		(fp_poly
			(pts
				(xy -2.5019 -4.02971) (xy -0.3302 -4.02971) (xy -0.3302 -6.30301) (xy -2.5019 -6.30301)
			)
			(stroke
				(width 0)
				(type default)
			)
			(fill yes)
			(layer "F.Paste")
		)
		(fp_poly
			(pts
				(xy -2.5019 -1.09601) (xy -0.3302 -1.09601) (xy -0.3302 -3.36931) (xy -2.5019 -3.36931)
			)
			(stroke
				(width 0)
				(type default)
			)
			(fill yes)
			(layer "F.Paste")
		)
		(fp_poly
			(pts
				(xy 0.3302 -4.02971) (xy 2.5019 -4.02971) (xy 2.5019 -6.30301) (xy 0.3302 -6.30301)
			)
			(stroke
				(width 0)
				(type default)
			)
			(fill yes)
			(layer "F.Paste")
		)
		(fp_poly
			(pts
				(xy 0.3302 -1.09601) (xy 2.5019 -1.09601) (xy 2.5019 -3.36931) (xy 0.3302 -3.36931)
			)
			(stroke
				(width 0)
				(type default)
			)
			(fill yes)
			(layer "F.Paste")
		)
		(fp_rect
			(start -2.4511 0.3048)
			(end 2.4511 -5.6896)
			(stroke
				(width 0)
				(type default)
			)
			(fill no)
			(layer "F.CrtYd")
		)
		(fp_poly
			(pts
				(xy -3.0099 1.3208) (xy -3.0099 -6.8072) (xy 3.0099 -6.8072) (xy 3.0099 -1.016) (xy 2.4511 -1.016)
				(xy 2.4511 -5.6896) (xy -2.4511 -5.6896) (xy -2.4511 0.3048) (xy 2.4511 0.3048) (xy 2.4511 -1.0033)
				(xy 3.0099 -1.0033) (xy 3.0099 1.3208)
			)
			(stroke
				(width 0)
				(type default)
			)
			(fill no)
			(layer "F.CrtYd")
		)
		(fp_rect
			(start -3.0099 1.3208)
			(end 3.0099 -6.8072)
			(stroke
				(width 0)
				(type default)
			)
			(fill no)
			(layer "F.Fab")
		)
		(pad "1" smd rect
			(at -1.905 0)
			(size 0.762 1.6256)
			(layers "F.Cu" "F.Mask" "F.Paste")
			(net "P12VU")
		)
		(pad "2" smd rect
			(at -0.635 0)
			(size 0.762 1.6256)
			(layers "F.Cu" "F.Mask" "F.Paste")
			(net "P12VU")
		)
		(pad "3" smd rect
			(at 0.635 0)
			(size 0.762 1.6256)
			(layers "F.Cu" "F.Mask" "F.Paste")
			(net "P12VU")
		)
		(pad "4" smd rect
			(at 1.905 0)
			(size 0.762 1.6256)
			(layers "F.Cu" "F.Mask" "F.Paste")
			(net "P12VU_2490_GATE_DRV")
		)
		(pad "5" smd rect
			(at 0 -3.69951)
			(size 5.0038 5.207)
			(layers "F.Cu" "F.Mask" "F.Paste")
			(net "P12VU_NET")
		)
	)
	(footprint ""
		(layer "F.Cu")
		(at 8.763 -69.1642 90)
		(property "Reference" "R166"
			(at 0 0 90)
			(layer "F.SilkS")
			(hide yes)
			(effects
				(font
					(size 1.27 1.27)
				)
			)
		)
		(property "Value" "4K7R2F-GP"
			(at 0.064008 -3.993896 90)
			(unlocked yes)
			(layer "F.Fab")
			(hide yes)
			(effects
				(font
					(size 1.016 1.016)
					(thickness 0.1524)
				)
			)
		)
		(property "Device Type" "R402H16"
			(at 0.064008 -5.517896 90)
			(unlocked yes)
			(layer "F.Fab")
			(hide yes)
			(effects
				(font
					(size 1.016 1.016)
					(thickness 0.1524)
				)
			)
		)
		(duplicate_pad_numbers_are_jumpers no)
		(fp_line
			(start 0.508 -0.9398)
			(end -0.508 -0.9398)
			(stroke
				(width 0.1524)
				(type default)
			)
			(layer "F.SilkS")
		)
		(fp_line
			(start -0.508 -0.9398)
			(end -0.508 0.9398)
			(stroke
				(width 0.1524)
				(type default)
			)
			(layer "F.SilkS")
		)
		(fp_rect
			(start -0.508 0.9398)
			(end 0.508 -0.9398)
			(stroke
				(width 0)
				(type default)
			)
			(fill no)
			(layer "F.CrtYd")
		)
		(fp_rect
			(start -0.508 0.9398)
			(end 0.508 -0.9398)
			(stroke
				(width 0)
				(type default)
			)
			(fill no)
			(layer "F.Fab")
		)
		(pad "1" smd custom
			(at 0 -0.4445 90)
			(size 0.1397 0.1397)
			(layers "F.Cu" "F.Mask" "F.Paste")
			(net "P3V3")
			(options
				(clearance outline)
				(anchor circle)
			)
			(primitives
				(gr_poly
					(pts
						(arc
							(start -0.1778 -0.2794)
							(mid -0.249642 -0.249642)
							(end -0.2794 -0.1778)
						)
						(arc
							(start -0.2794 0.1778)
							(mid -0.249642 0.249642)
							(end -0.1778 0.2794)
						)
						(arc
							(start 0.1778 0.2794)
							(mid 0.249642 0.249642)
							(end 0.2794 0.1778)
						)
						(arc
							(start 0.2794 -0.1778)
							(mid 0.249642 -0.249642)
							(end 0.1778 -0.2794)
						)
					)
					(width 0)
					(fill yes)
				)
			)
		)
		(pad "2" smd custom
			(at 0 0.4445 90)
			(size 0.1397 0.1397)
			(layers "F.Cu" "F.Mask" "F.Paste")
			(net "PWM_BUFFER_IN_FAN3_FAN4")
			(options
				(clearance outline)
				(anchor circle)
			)
			(primitives
				(gr_poly
					(pts
						(arc
							(start -0.1778 -0.2794)
							(mid -0.249642 -0.249642)
							(end -0.2794 -0.1778)
						)
						(arc
							(start -0.2794 0.1778)
							(mid -0.249642 0.249642)
							(end -0.1778 0.2794)
						)
						(arc
							(start 0.1778 0.2794)
							(mid 0.249642 0.249642)
							(end 0.2794 0.1778)
						)
						(arc
							(start 0.2794 -0.1778)
							(mid 0.249642 -0.249642)
							(end 0.1778 -0.2794)
						)
					)
					(width 0)
					(fill yes)
				)
			)
		)
	)
	(footprint ""
		(layer "F.Cu")
		(at 14.8844 -50.6222 90)
		(property "Reference" "R175"
			(at 0 0 90)
			(layer "F.SilkS")
			(hide yes)
			(effects
				(font
					(size 1.27 1.27)
				)
			)
		)
		(property "Value" "0R2J-2-GP"
			(at 0.064008 -3.993896 90)
			(unlocked yes)
			(layer "F.Fab")
			(hide yes)
			(effects
				(font
					(size 1.016 1.016)
					(thickness 0.1524)
				)
			)
		)
		(property "Device Type" "R402H16"
			(at 0.064008 -5.517896 90)
			(unlocked yes)
			(layer "F.Fab")
			(hide yes)
			(effects
				(font
					(size 1.016 1.016)
					(thickness 0.1524)
				)
			)
		)
		(duplicate_pad_numbers_are_jumpers no)
		(fp_line
			(start 0.508 -0.9398)
			(end -0.508 -0.9398)
			(stroke
				(width 0.1524)
				(type default)
			)
			(layer "F.SilkS")
		)
		(fp_line
			(start -0.508 -0.9398)
			(end -0.508 0.9398)
			(stroke
				(width 0.1524)
				(type default)
			)
			(layer "F.SilkS")
		)
		(fp_rect
			(start -0.508 0.9398)
			(end 0.508 -0.9398)
			(stroke
				(width 0)
				(type default)
			)
			(fill no)
			(layer "F.CrtYd")
		)
		(fp_rect
			(start -0.508 0.9398)
			(end 0.508 -0.9398)
			(stroke
				(width 0)
				(type default)
			)
			(fill no)
			(layer "F.Fab")
		)
		(pad "1" smd custom
			(at 0 -0.4445 90)
			(size 0.1397 0.1397)
			(layers "F.Cu" "F.Mask" "F.Paste")
			(net "SD_LATCH_RELEASE_U")
			(options
				(clearance outline)
				(anchor circle)
			)
			(primitives
				(gr_poly
					(pts
						(arc
							(start -0.1778 -0.2794)
							(mid -0.249642 -0.249642)
							(end -0.2794 -0.1778)
						)
						(arc
							(start -0.2794 0.1778)
							(mid -0.249642 0.249642)
							(end -0.1778 0.2794)
						)
						(arc
							(start 0.1778 0.2794)
							(mid 0.249642 0.249642)
							(end 0.2794 0.1778)
						)
						(arc
							(start 0.2794 -0.1778)
							(mid 0.249642 -0.249642)
							(end 0.1778 -0.2794)
						)
					)
					(width 0)
					(fill yes)
				)
			)
		)
		(pad "2" smd custom
			(at 0 0.4445 90)
			(size 0.1397 0.1397)
			(layers "F.Cu" "F.Mask" "F.Paste")
			(net "TEMP_ALM#_REVERSE_R")
			(options
				(clearance outline)
				(anchor circle)
			)
			(primitives
				(gr_poly
					(pts
						(arc
							(start -0.1778 -0.2794)
							(mid -0.249642 -0.249642)
							(end -0.2794 -0.1778)
						)
						(arc
							(start -0.2794 0.1778)
							(mid -0.249642 0.249642)
							(end -0.1778 0.2794)
						)
						(arc
							(start 0.1778 0.2794)
							(mid 0.249642 0.249642)
							(end 0.2794 0.1778)
						)
						(arc
							(start 0.2794 -0.1778)
							(mid 0.249642 -0.249642)
							(end 0.1778 -0.2794)
						)
					)
					(width 0)
					(fill yes)
				)
			)
		)
	)
	(footprint ""
		(layer "F.Cu")
		(at 29.7942 -238.252 180)
		(property "Reference" "R40"
			(at 0 0 180)
			(layer "F.SilkS")
			(hide yes)
			(effects
				(font
					(size 1.27 1.27)
				)
			)
		)
		(property "Value" "4K7R2J-2-GP"
			(at 0.064008 -3.993896 180)
			(unlocked yes)
			(layer "F.Fab")
			(hide yes)
			(effects
				(font
					(size 1.016 1.016)
					(thickness 0.1524)
				)
			)
		)
		(property "Device Type" "R402H16"
			(at 0.064008 -5.517896 180)
			(unlocked yes)
			(layer "F.Fab")
			(hide yes)
			(effects
				(font
					(size 1.016 1.016)
					(thickness 0.1524)
				)
			)
		)
		(duplicate_pad_numbers_are_jumpers no)
		(fp_line
			(start 0.508 -0.9398)
			(end -0.508 -0.9398)
			(stroke
				(width 0.1524)
				(type default)
			)
			(layer "F.SilkS")
		)
		(fp_line
			(start -0.508 -0.9398)
			(end -0.508 0.9398)
			(stroke
				(width 0.1524)
				(type default)
			)
			(layer "F.SilkS")
		)
		(fp_rect
			(start -0.508 0.9398)
			(end 0.508 -0.9398)
			(stroke
				(width 0)
				(type default)
			)
			(fill no)
			(layer "F.CrtYd")
		)
		(fp_rect
			(start -0.508 0.9398)
			(end 0.508 -0.9398)
			(stroke
				(width 0)
				(type default)
			)
			(fill no)
			(layer "F.Fab")
		)
		(pad "1" smd custom
			(at 0 -0.4445 180)
			(size 0.1397 0.1397)
			(layers "F.Cu" "F.Mask" "F.Paste")
			(net "P3V3")
			(options
				(clearance outline)
				(anchor circle)
			)
			(primitives
				(gr_poly
					(pts
						(arc
							(start -0.1778 -0.2794)
							(mid -0.249642 -0.249642)
							(end -0.2794 -0.1778)
						)
						(arc
							(start -0.2794 0.1778)
							(mid -0.249642 0.249642)
							(end -0.1778 0.2794)
						)
						(arc
							(start 0.1778 0.2794)
							(mid 0.249642 0.249642)
							(end 0.2794 0.1778)
						)
						(arc
							(start 0.2794 -0.1778)
							(mid 0.249642 -0.249642)
							(end 0.1778 -0.2794)
						)
					)
					(width 0)
					(fill yes)
				)
			)
		)
		(pad "2" smd custom
			(at 0 0.4445 180)
			(size 0.1397 0.1397)
			(layers "F.Cu" "F.Mask" "F.Paste")
			(net "FCB_EEPROM_A1")
			(options
				(clearance outline)
				(anchor circle)
			)
			(primitives
				(gr_poly
					(pts
						(arc
							(start -0.1778 -0.2794)
							(mid -0.249642 -0.249642)
							(end -0.2794 -0.1778)
						)
						(arc
							(start -0.2794 0.1778)
							(mid -0.249642 0.249642)
							(end -0.1778 0.2794)
						)
						(arc
							(start 0.1778 0.2794)
							(mid 0.249642 0.249642)
							(end 0.2794 0.1778)
						)
						(arc
							(start 0.2794 -0.1778)
							(mid 0.249642 -0.249642)
							(end 0.1778 -0.2794)
						)
					)
					(width 0)
					(fill yes)
				)
			)
		)
	)
	(footprint ""
		(layer "F.Cu")
		(at 22.1996 -146.2786 180)
		(property "Reference" "PC93"
			(at 0 0 180)
			(layer "F.SilkS")
			(hide yes)
			(effects
				(font
					(size 1.27 1.27)
				)
			)
		)
		(property "Value" "SC220P50V2KX-3GP"
			(at 1.1811 -2.7051 180)
			(unlocked yes)
			(layer "F.Fab")
			(hide yes)
			(effects
				(font
					(size 1.016 1.016)
					(thickness 0.1524)
				)
			)
		)
		(property "Device Type" "C402H22"
			(at 1.1811 -4.2291 180)
			(unlocked yes)
			(layer "F.Fab")
			(hide yes)
			(effects
				(font
					(size 1.016 1.016)
					(thickness 0.1524)
				)
			)
		)
		(duplicate_pad_numbers_are_jumpers no)
		(fp_rect
			(start -0.4318 0.9525)
			(end 0.4318 -0.9525)
			(stroke
				(width 0)
				(type default)
			)
			(fill no)
			(layer "F.CrtYd")
		)
		(fp_rect
			(start -0.4318 0.9525)
			(end 0.4318 -0.9525)
			(stroke
				(width 0)
				(type default)
			)
			(fill no)
			(layer "F.Fab")
		)
		(pad "1" smd custom
			(at 0 -0.4445 180)
			(size 0.1524 0.1524)
			(layers "F.Cu" "F.Mask" "F.Paste")
			(net "P12VU_2490_VREF")
			(options
				(clearance outline)
				(anchor circle)
			)
			(primitives
				(gr_poly
					(pts
						(arc
							(start 0.3048 -0.2032)
							(mid 0.275042 -0.275042)
							(end 0.2032 -0.3048)
						)
						(arc
							(start -0.2032 -0.3048)
							(mid -0.275042 -0.275042)
							(end -0.3048 -0.2032)
						)
						(arc
							(start -0.3048 0.2032)
							(mid -0.275042 0.275042)
							(end -0.2032 0.3048)
						)
						(arc
							(start 0.2032 0.3048)
							(mid 0.275042 0.275042)
							(end 0.3048 0.2032)
						)
					)
					(width 0)
					(fill yes)
				)
			)
		)
		(pad "2" smd custom
			(at 0 0.4445 180)
			(size 0.1524 0.1524)
			(layers "F.Cu" "F.Mask" "F.Paste")
			(net "GND")
			(options
				(clearance outline)
				(anchor circle)
			)
			(primitives
				(gr_poly
					(pts
						(arc
							(start 0.3048 -0.2032)
							(mid 0.275042 -0.275042)
							(end 0.2032 -0.3048)
						)
						(arc
							(start -0.2032 -0.3048)
							(mid -0.275042 -0.275042)
							(end -0.3048 -0.2032)
						)
						(arc
							(start -0.3048 0.2032)
							(mid -0.275042 0.275042)
							(end -0.2032 0.3048)
						)
						(arc
							(start 0.2032 0.3048)
							(mid 0.275042 0.275042)
							(end 0.3048 0.2032)
						)
					)
					(width 0)
					(fill yes)
				)
			)
		)
	)
	(footprint ""
		(layer "F.Cu")
		(at 35.687 -240.3094 180)
		(property "Reference" "R56"
			(at 0 0 180)
			(layer "F.SilkS")
			(hide yes)
			(effects
				(font
					(size 1.27 1.27)
				)
			)
		)
		(property "Value" "4K7R2J-2-GP"
			(at 0.064008 -3.993896 180)
			(unlocked yes)
			(layer "F.Fab")
			(hide yes)
			(effects
				(font
					(size 1.016 1.016)
					(thickness 0.1524)
				)
			)
		)
		(property "Device Type" "R402H16"
			(at 0.064008 -5.517896 180)
			(unlocked yes)
			(layer "F.Fab")
			(hide yes)
			(effects
				(font
					(size 1.016 1.016)
					(thickness 0.1524)
				)
			)
		)
		(duplicate_pad_numbers_are_jumpers no)
		(fp_line
			(start 0.508 -0.9398)
			(end -0.508 -0.9398)
			(stroke
				(width 0.1524)
				(type default)
			)
			(layer "F.SilkS")
		)
		(fp_line
			(start -0.508 -0.9398)
			(end -0.508 0.9398)
			(stroke
				(width 0.1524)
				(type default)
			)
			(layer "F.SilkS")
		)
		(fp_rect
			(start -0.508 0.9398)
			(end 0.508 -0.9398)
			(stroke
				(width 0)
				(type default)
			)
			(fill no)
			(layer "F.CrtYd")
		)
		(fp_rect
			(start -0.508 0.9398)
			(end 0.508 -0.9398)
			(stroke
				(width 0)
				(type default)
			)
			(fill no)
			(layer "F.Fab")
		)
		(pad "1" smd custom
			(at 0 -0.4445 180)
			(size 0.1397 0.1397)
			(layers "F.Cu" "F.Mask" "F.Paste")
			(net "GND")
			(options
				(clearance outline)
				(anchor circle)
			)
			(primitives
				(gr_poly
					(pts
						(arc
							(start -0.1778 -0.2794)
							(mid -0.249642 -0.249642)
							(end -0.2794 -0.1778)
						)
						(arc
							(start -0.2794 0.1778)
							(mid -0.249642 0.249642)
							(end -0.1778 0.2794)
						)
						(arc
							(start 0.1778 0.2794)
							(mid 0.249642 0.249642)
							(end 0.2794 0.1778)
						)
						(arc
							(start 0.2794 -0.1778)
							(mid 0.249642 -0.249642)
							(end 0.1778 -0.2794)
						)
					)
					(width 0)
					(fill yes)
				)
			)
		)
		(pad "2" smd custom
			(at 0 0.4445 180)
			(size 0.1397 0.1397)
			(layers "F.Cu" "F.Mask" "F.Paste")
			(net "LED_DRV_A2")
			(options
				(clearance outline)
				(anchor circle)
			)
			(primitives
				(gr_poly
					(pts
						(arc
							(start -0.1778 -0.2794)
							(mid -0.249642 -0.249642)
							(end -0.2794 -0.1778)
						)
						(arc
							(start -0.2794 0.1778)
							(mid -0.249642 0.249642)
							(end -0.1778 0.2794)
						)
						(arc
							(start 0.1778 0.2794)
							(mid 0.249642 0.249642)
							(end 0.2794 0.1778)
						)
						(arc
							(start 0.2794 -0.1778)
							(mid 0.249642 -0.249642)
							(end 0.1778 -0.2794)
						)
					)
					(width 0)
					(fill yes)
				)
			)
		)
	)
	(footprint ""
		(layer "F.Cu")
		(at 20.828 -179.1716 180)
		(property "Reference" "R87"
			(at 0 0 180)
			(layer "F.SilkS")
			(hide yes)
			(effects
				(font
					(size 1.27 1.27)
				)
			)
		)
		(property "Value" "27KR3F-GP"
			(at -0.0254 -2.5146 180)
			(unlocked yes)
			(layer "F.Fab")
			(hide yes)
			(effects
				(font
					(size 1.016 1.016)
					(thickness 0.1524)
				)
			)
		)
		(property "Device Type" "R603H22"
			(at -0.0254 -4.0386 180)
			(unlocked yes)
			(layer "F.Fab")
			(hide yes)
			(effects
				(font
					(size 1.016 1.016)
					(thickness 0.1524)
				)
			)
		)
		(duplicate_pad_numbers_are_jumpers no)
		(fp_line
			(start 0.2032 0)
			(end 0.4826 0)
			(stroke
				(width 0.2032)
				(type default)
			)
			(layer "F.SilkS")
		)
		(fp_line
			(start -0.4826 0)
			(end -0.2032 0)
			(stroke
				(width 0.2032)
				(type default)
			)
			(layer "F.SilkS")
		)
		(fp_rect
			(start -0.5842 1.3335)
			(end 0.5842 -1.3335)
			(stroke
				(width 0)
				(type default)
			)
			(fill no)
			(layer "F.CrtYd")
		)
		(fp_rect
			(start -0.5842 1.3335)
			(end 0.5842 -1.3335)
			(stroke
				(width 0)
				(type default)
			)
			(fill no)
			(layer "F.Fab")
		)
		(pad "1" smd custom
			(at 0 -0.762 180)
			(size 0.2159 0.2159)
			(layers "F.Cu" "F.Mask" "F.Paste")
			(net "FANIN_7")
			(options
				(clearance outline)
				(anchor circle)
			)
			(primitives
				(gr_poly
					(pts
						(arc
							(start -0.3302 -0.4318)
							(mid -0.402042 -0.402042)
							(end -0.4318 -0.3302)
						)
						(arc
							(start -0.4318 0.3302)
							(mid -0.402042 0.402042)
							(end -0.3302 0.4318)
						)
						(arc
							(start 0.3302 0.4318)
							(mid 0.402042 0.402042)
							(end 0.4318 0.3302)
						)
						(arc
							(start 0.4318 -0.3302)
							(mid 0.402042 -0.402042)
							(end 0.3302 -0.4318)
						)
					)
					(width 0)
					(fill yes)
				)
			)
		)
		(pad "2" smd custom
			(at 0 0.762 180)
			(size 0.2159 0.2159)
			(layers "F.Cu" "F.Mask" "F.Paste")
			(net "FAN_TACH7")
			(options
				(clearance outline)
				(anchor circle)
			)
			(primitives
				(gr_poly
					(pts
						(arc
							(start -0.3302 -0.4318)
							(mid -0.402042 -0.402042)
							(end -0.4318 -0.3302)
						)
						(arc
							(start -0.4318 0.3302)
							(mid -0.402042 0.402042)
							(end -0.3302 0.4318)
						)
						(arc
							(start 0.3302 0.4318)
							(mid 0.402042 0.402042)
							(end 0.4318 0.3302)
						)
						(arc
							(start 0.4318 -0.3302)
							(mid 0.402042 -0.402042)
							(end 0.3302 -0.4318)
						)
					)
					(width 0)
					(fill yes)
				)
			)
		)
	)
)
